(kicad_pcb
	(version 20260206)
	(generator "pcbnew")
	(generator_version "10.0")
	(general
		(thickness 1.6)
		(legacy_teardrops no)
	)
	(paper "A4")
	(title_block
		(title "dpb — 14545-sa.0730WZS0815.brd")
		(comment 1 "Honey Badger (Wiwynn) / footprints 564-570 of 1066")
	)
	(layers
		(0 "F.Cu" signal "TOP")
		(4 "In1.Cu" signal "L2GND")
		(6 "In2.Cu" signal "L3")
		(8 "In3.Cu" signal "L4VCC")
		(10 "In4.Cu" signal "L5VCC")
		(12 "In5.Cu" signal "L6")
		(14 "In6.Cu" signal "L7GND")
		(2 "B.Cu" signal "BOTTOM")
		(9 "F.Adhes" user "F.Adhesive")
		(11 "B.Adhes" user "B.Adhesive")
		(13 "F.Paste" user "Package Geometry/Pastemask Top")
		(15 "B.Paste" user "Package Geometry/Pastemask Bottom")
		(5 "F.SilkS" user "Ref Des/Silkscreen Top")
		(7 "B.SilkS" user "Ref Des/Silkscreen Bottom")
		(1 "F.Mask" user "Board Geometry/Soldermask Top")
		(3 "B.Mask" user "Board Geometry/Soldermask Bottom")
		(17 "Dwgs.User" user "User.Drawings")
		(19 "Cmts.User" user "User.Comments")
		(21 "Eco1.User" user "User.Eco1")
		(23 "Eco2.User" user "User.Eco2")
		(25 "Edge.Cuts" user "Board Geometry/Outline")
		(27 "Margin" user)
		(31 "F.CrtYd" user "Package Geometry/Place Bound Top")
		(29 "B.CrtYd" user "Package Geometry/Place Bound Bottom")
		(35 "F.Fab" user "Ref Des/Assembly Top")
		(33 "B.Fab" user "Ref Des/Assembly Bottom")
	)
	(footprint ""
		(layer "F.Cu")
		(at 85.781134 -493.625886 -90)
		(property "Reference" "R445"
			(at 0 0 270)
			(layer "F.SilkS")
			(hide yes)
			(effects
				(font
					(size 1.27 1.27)
				)
			)
		)
		(property "Value" "4K7R2J-2-GP"
			(at 0.064008 -3.993896 270)
			(unlocked yes)
			(layer "F.Fab")
			(hide yes)
			(effects
				(font
					(size 1.016 1.016)
					(thickness 0.1524)
				)
			)
		)
		(property "Device Type" "R402H16"
			(at 0.064008 -5.517896 270)
			(unlocked yes)
			(layer "F.Fab")
			(hide yes)
			(effects
				(font
					(size 1.016 1.016)
					(thickness 0.1524)
				)
			)
		)
		(duplicate_pad_numbers_are_jumpers no)
		(fp_line
			(start -0.508 -0.9398)
			(end -0.508 0.9398)
			(stroke
				(width 0.1524)
				(type default)
			)
			(layer "F.SilkS")
		)
		(fp_line
			(start 0.508 -0.9398)
			(end -0.508 -0.9398)
			(stroke
				(width 0.1524)
				(type default)
			)
			(layer "F.SilkS")
		)
		(fp_rect
			(start -0.508 0.9398)
			(end 0.508 -0.9398)
			(stroke
				(width 0)
				(type default)
			)
			(fill no)
			(layer "F.CrtYd")
		)
		(fp_rect
			(start -0.508 0.9398)
			(end 0.508 -0.9398)
			(stroke
				(width 0)
				(type default)
			)
			(fill no)
			(layer "F.Fab")
		)
		(pad "1" smd custom
			(at 0 -0.4445 270)
			(size 0.1397 0.1397)
			(layers "F.Cu" "F.Mask" "F.Paste")
			(net "P3V3")
			(options
				(clearance outline)
				(anchor circle)
			)
			(primitives
				(gr_poly
					(pts
						(arc
							(start -0.1778 -0.2794)
							(mid -0.249642 -0.249642)
							(end -0.2794 -0.1778)
						)
						(arc
							(start -0.2794 0.1778)
							(mid -0.249642 0.249642)
							(end -0.1778 0.2794)
						)
						(arc
							(start 0.1778 0.2794)
							(mid 0.249642 0.249642)
							(end 0.2794 0.1778)
						)
						(arc
							(start 0.2794 -0.1778)
							(mid 0.249642 -0.249642)
							(end 0.1778 -0.2794)
						)
					)
					(width 0)
					(fill yes)
				)
			)
		)
		(pad "2" smd custom
			(at 0 0.4445 270)
			(size 0.1397 0.1397)
			(layers "F.Cu" "F.Mask" "F.Paste")
			(net "SAS_EXP_B_PWR5")
			(options
				(clearance outline)
				(anchor circle)
			)
			(primitives
				(gr_poly
					(pts
						(arc
							(start -0.1778 -0.2794)
							(mid -0.249642 -0.249642)
							(end -0.2794 -0.1778)
						)
						(arc
							(start -0.2794 0.1778)
							(mid -0.249642 0.249642)
							(end -0.1778 0.2794)
						)
						(arc
							(start 0.1778 0.2794)
							(mid 0.249642 0.249642)
							(end 0.2794 0.1778)
						)
						(arc
							(start 0.2794 -0.1778)
							(mid 0.249642 -0.249642)
							(end 0.1778 -0.2794)
						)
					)
					(width 0)
					(fill yes)
				)
			)
		)
	)
	(footprint ""
		(layer "F.Cu")
		(at 21.742146 -254.1143 90)
		(property "Reference" "R371"
			(at 0 0 90)
			(layer "F.SilkS")
			(hide yes)
			(effects
				(font
					(size 1.27 1.27)
				)
			)
		)
		(property "Value" "4K7R2J-2-GP"
			(at 0.064008 -3.993896 90)
			(unlocked yes)
			(layer "F.Fab")
			(hide yes)
			(effects
				(font
					(size 1.016 1.016)
					(thickness 0.1524)
				)
			)
		)
		(property "Device Type" "R402H16"
			(at 0.064008 -5.517896 90)
			(unlocked yes)
			(layer "F.Fab")
			(hide yes)
			(effects
				(font
					(size 1.016 1.016)
					(thickness 0.1524)
				)
			)
		)
		(duplicate_pad_numbers_are_jumpers no)
		(fp_line
			(start 0.508 -0.9398)
			(end -0.508 -0.9398)
			(stroke
				(width 0.1524)
				(type default)
			)
			(layer "F.SilkS")
		)
		(fp_line
			(start -0.508 -0.9398)
			(end -0.508 0.9398)
			(stroke
				(width 0.1524)
				(type default)
			)
			(layer "F.SilkS")
		)
		(fp_rect
			(start -0.508 0.9398)
			(end 0.508 -0.9398)
			(stroke
				(width 0)
				(type default)
			)
			(fill no)
			(layer "F.CrtYd")
		)
		(fp_rect
			(start -0.508 0.9398)
			(end 0.508 -0.9398)
			(stroke
				(width 0)
				(type default)
			)
			(fill no)
			(layer "F.Fab")
		)
		(pad "1" smd custom
			(at 0 -0.4445 90)
			(size 0.1397 0.1397)
			(layers "F.Cu" "F.Mask" "F.Paste")
			(net "P3V3")
			(options
				(clearance outline)
				(anchor circle)
			)
			(primitives
				(gr_poly
					(pts
						(arc
							(start -0.1778 -0.2794)
							(mid -0.249642 -0.249642)
							(end -0.2794 -0.1778)
						)
						(arc
							(start -0.2794 0.1778)
							(mid -0.249642 0.249642)
							(end -0.1778 0.2794)
						)
						(arc
							(start 0.1778 0.2794)
							(mid 0.249642 0.249642)
							(end 0.2794 0.1778)
						)
						(arc
							(start 0.2794 -0.1778)
							(mid 0.249642 -0.249642)
							(end 0.1778 -0.2794)
						)
					)
					(width 0)
					(fill yes)
				)
			)
		)
		(pad "2" smd custom
			(at 0 0.4445 90)
			(size 0.1397 0.1397)
			(layers "F.Cu" "F.Mask" "F.Paste")
			(net "I2C_D_SCL")
			(options
				(clearance outline)
				(anchor circle)
			)
			(primitives
				(gr_poly
					(pts
						(arc
							(start -0.1778 -0.2794)
							(mid -0.249642 -0.249642)
							(end -0.2794 -0.1778)
						)
						(arc
							(start -0.2794 0.1778)
							(mid -0.249642 0.249642)
							(end -0.1778 0.2794)
						)
						(arc
							(start 0.1778 0.2794)
							(mid 0.249642 0.249642)
							(end 0.2794 0.1778)
						)
						(arc
							(start 0.2794 -0.1778)
							(mid 0.249642 -0.249642)
							(end 0.1778 -0.2794)
						)
					)
					(width 0)
					(fill yes)
				)
			)
		)
	)
	(footprint ""
		(layer "F.Cu")
		(at 27.2923 -341.5284 -90)
		(property "Reference" "C38"
			(at 0 0 270)
			(layer "F.SilkS")
			(hide yes)
			(effects
				(font
					(size 1.27 1.27)
				)
			)
		)
		(property "Value" "SCD01U50V2KX-1GP"
			(at 1.1811 -2.7051 270)
			(unlocked yes)
			(layer "F.Fab")
			(hide yes)
			(effects
				(font
					(size 1.016 1.016)
					(thickness 0.1524)
				)
			)
		)
		(property "Device Type" "C402H22"
			(at 1.1811 -4.2291 270)
			(unlocked yes)
			(layer "F.Fab")
			(hide yes)
			(effects
				(font
					(size 1.016 1.016)
					(thickness 0.1524)
				)
			)
		)
		(duplicate_pad_numbers_are_jumpers no)
		(fp_rect
			(start -0.4318 0.9525)
			(end 0.4318 -0.9525)
			(stroke
				(width 0)
				(type default)
			)
			(fill no)
			(layer "F.CrtYd")
		)
		(fp_rect
			(start -0.4318 0.9525)
			(end 0.4318 -0.9525)
			(stroke
				(width 0)
				(type default)
			)
			(fill no)
			(layer "F.Fab")
		)
		(pad "1" smd custom
			(at 0 -0.4445 270)
			(size 0.1524 0.1524)
			(layers "F.Cu" "F.Mask" "F.Paste")
			(net "SEB_AB_TX+")
			(options
				(clearance outline)
				(anchor circle)
			)
			(primitives
				(gr_poly
					(pts
						(arc
							(start 0.3048 -0.2032)
							(mid 0.275042 -0.275042)
							(end 0.2032 -0.3048)
						)
						(arc
							(start -0.2032 -0.3048)
							(mid -0.275042 -0.275042)
							(end -0.3048 -0.2032)
						)
						(arc
							(start -0.3048 0.2032)
							(mid -0.275042 0.275042)
							(end -0.2032 0.3048)
						)
						(arc
							(start 0.2032 0.3048)
							(mid 0.275042 0.275042)
							(end 0.3048 0.2032)
						)
					)
					(width 0)
					(fill yes)
				)
			)
		)
		(pad "2" smd custom
			(at 0 0.4445 270)
			(size 0.1524 0.1524)
			(layers "F.Cu" "F.Mask" "F.Paste")
			(net "SEB_AB_RX+")
			(options
				(clearance outline)
				(anchor circle)
			)
			(primitives
				(gr_poly
					(pts
						(arc
							(start 0.3048 -0.2032)
							(mid 0.275042 -0.275042)
							(end 0.2032 -0.3048)
						)
						(arc
							(start -0.2032 -0.3048)
							(mid -0.275042 -0.275042)
							(end -0.3048 -0.2032)
						)
						(arc
							(start -0.3048 0.2032)
							(mid -0.275042 0.275042)
							(end -0.2032 0.3048)
						)
						(arc
							(start 0.2032 0.3048)
							(mid 0.275042 0.275042)
							(end 0.3048 0.2032)
						)
					)
					(width 0)
					(fill yes)
				)
			)
		)
	)
	(footprint ""
		(layer "F.Cu")
		(at 8.636 -269.24)
		(property "Reference" "R502"
			(at 0 0 0)
			(layer "F.SilkS")
			(hide yes)
			(effects
				(font
					(size 1.27 1.27)
				)
			)
		)
		(property "Value" "1KR2F-3-GP"
			(at 0.064008 -3.993896 0)
			(unlocked yes)
			(layer "F.Fab")
			(hide yes)
			(effects
				(font
					(size 1.016 1.016)
					(thickness 0.1524)
				)
			)
		)
		(property "Device Type" "R402H16"
			(at 0.064008 -5.517896 0)
			(unlocked yes)
			(layer "F.Fab")
			(hide yes)
			(effects
				(font
					(size 1.016 1.016)
					(thickness 0.1524)
				)
			)
		)
		(duplicate_pad_numbers_are_jumpers no)
		(fp_line
			(start -0.508 -0.9398)
			(end -0.508 0.9398)
			(stroke
				(width 0.1524)
				(type default)
			)
			(layer "F.SilkS")
		)
		(fp_line
			(start 0.508 -0.9398)
			(end -0.508 -0.9398)
			(stroke
				(width 0.1524)
				(type default)
			)
			(layer "F.SilkS")
		)
		(fp_rect
			(start -0.508 0.9398)
			(end 0.508 -0.9398)
			(stroke
				(width 0)
				(type default)
			)
			(fill no)
			(layer "F.CrtYd")
		)
		(fp_rect
			(start -0.508 0.9398)
			(end 0.508 -0.9398)
			(stroke
				(width 0)
				(type default)
			)
			(fill no)
			(layer "F.Fab")
		)
		(pad "1" smd custom
			(at 0 -0.4445)
			(size 0.1397 0.1397)
			(layers "F.Cu" "F.Mask" "F.Paste")
			(net "FLT_HDD12_B")
			(options
				(clearance outline)
				(anchor circle)
			)
			(primitives
				(gr_poly
					(pts
						(arc
							(start -0.1778 -0.2794)
							(mid -0.249642 -0.249642)
							(end -0.2794 -0.1778)
						)
						(arc
							(start -0.2794 0.1778)
							(mid -0.249642 0.249642)
							(end -0.1778 0.2794)
						)
						(arc
							(start 0.1778 0.2794)
							(mid 0.249642 0.249642)
							(end 0.2794 0.1778)
						)
						(arc
							(start 0.2794 -0.1778)
							(mid 0.249642 -0.249642)
							(end 0.1778 -0.2794)
						)
					)
					(width 0)
					(fill yes)
				)
			)
		)
		(pad "2" smd custom
			(at 0 0.4445)
			(size 0.1397 0.1397)
			(layers "F.Cu" "F.Mask" "F.Paste")
			(net "FLT_HDD12_DRIVE")
			(options
				(clearance outline)
				(anchor circle)
			)
			(primitives
				(gr_poly
					(pts
						(arc
							(start -0.1778 -0.2794)
							(mid -0.249642 -0.249642)
							(end -0.2794 -0.1778)
						)
						(arc
							(start -0.2794 0.1778)
							(mid -0.249642 0.249642)
							(end -0.1778 0.2794)
						)
						(arc
							(start 0.1778 0.2794)
							(mid 0.249642 0.249642)
							(end 0.2794 0.1778)
						)
						(arc
							(start 0.2794 -0.1778)
							(mid 0.249642 -0.249642)
							(end 0.1778 -0.2794)
						)
					)
					(width 0)
					(fill yes)
				)
			)
		)
	)
	(footprint ""
		(layer "F.Cu")
		(at 34.926016 -441.280042 180)
		(property "Reference" "C269"
			(at 0 0 180)
			(layer "F.SilkS")
			(hide yes)
			(effects
				(font
					(size 1.27 1.27)
				)
			)
		)
		(property "Value" "SCD1U10V2KX-5GP"
			(at 1.1811 -2.7051 180)
			(unlocked yes)
			(layer "F.Fab")
			(hide yes)
			(effects
				(font
					(size 1.016 1.016)
					(thickness 0.1524)
				)
			)
		)
		(property "Device Type" "C402H22"
			(at 1.1811 -4.2291 180)
			(unlocked yes)
			(layer "F.Fab")
			(hide yes)
			(effects
				(font
					(size 1.016 1.016)
					(thickness 0.1524)
				)
			)
		)
		(duplicate_pad_numbers_are_jumpers no)
		(fp_rect
			(start -0.4318 0.9525)
			(end 0.4318 -0.9525)
			(stroke
				(width 0)
				(type default)
			)
			(fill no)
			(layer "F.CrtYd")
		)
		(fp_rect
			(start -0.4318 0.9525)
			(end 0.4318 -0.9525)
			(stroke
				(width 0)
				(type default)
			)
			(fill no)
			(layer "F.Fab")
		)
		(pad "1" smd custom
			(at 0 -0.4445 180)
			(size 0.1524 0.1524)
			(layers "F.Cu" "F.Mask" "F.Paste")
			(net "P3V3")
			(options
				(clearance outline)
				(anchor circle)
			)
			(primitives
				(gr_poly
					(pts
						(arc
							(start 0.3048 -0.2032)
							(mid 0.275042 -0.275042)
							(end 0.2032 -0.3048)
						)
						(arc
							(start -0.2032 -0.3048)
							(mid -0.275042 -0.275042)
							(end -0.3048 -0.2032)
						)
						(arc
							(start -0.3048 0.2032)
							(mid -0.275042 0.275042)
							(end -0.2032 0.3048)
						)
						(arc
							(start 0.2032 0.3048)
							(mid 0.275042 0.275042)
							(end 0.3048 0.2032)
						)
					)
					(width 0)
					(fill yes)
				)
			)
		)
		(pad "2" smd custom
			(at 0 0.4445 180)
			(size 0.1524 0.1524)
			(layers "F.Cu" "F.Mask" "F.Paste")
			(net "GND")
			(options
				(clearance outline)
				(anchor circle)
			)
			(primitives
				(gr_poly
					(pts
						(arc
							(start 0.3048 -0.2032)
							(mid 0.275042 -0.275042)
							(end 0.2032 -0.3048)
						)
						(arc
							(start -0.2032 -0.3048)
							(mid -0.275042 -0.275042)
							(end -0.3048 -0.2032)
						)
						(arc
							(start -0.3048 0.2032)
							(mid -0.275042 0.275042)
							(end -0.2032 0.3048)
						)
						(arc
							(start 0.2032 0.3048)
							(mid 0.275042 0.275042)
							(end 0.3048 0.2032)
						)
					)
					(width 0)
					(fill yes)
				)
			)
		)
	)
	(footprint ""
		(layer "F.Cu")
		(at 44.449746 -18.5547 180)
		(property "Reference" "PR50"
			(at 0 0 180)
			(layer "F.SilkS")
			(hide yes)
			(effects
				(font
					(size 1.27 1.27)
				)
			)
		)
		(property "Value" "10KR2F-2-GP"
			(at 0.064008 -3.993896 180)
			(unlocked yes)
			(layer "F.Fab")
			(hide yes)
			(effects
				(font
					(size 1.016 1.016)
					(thickness 0.1524)
				)
			)
		)
		(property "Device Type" "R402H16"
			(at 0.064008 -5.517896 180)
			(unlocked yes)
			(layer "F.Fab")
			(hide yes)
			(effects
				(font
					(size 1.016 1.016)
					(thickness 0.1524)
				)
			)
		)
		(duplicate_pad_numbers_are_jumpers no)
		(fp_line
			(start 0.508 -0.9398)
			(end -0.508 -0.9398)
			(stroke
				(width 0.1524)
				(type default)
			)
			(layer "F.SilkS")
		)
		(fp_line
			(start -0.508 -0.9398)
			(end -0.508 0.9398)
			(stroke
				(width 0.1524)
				(type default)
			)
			(layer "F.SilkS")
		)
		(fp_rect
			(start -0.508 0.9398)
			(end 0.508 -0.9398)
			(stroke
				(width 0)
				(type default)
			)
			(fill no)
			(layer "F.CrtYd")
		)
		(fp_rect
			(start -0.508 0.9398)
			(end 0.508 -0.9398)
			(stroke
				(width 0)
				(type default)
			)
			(fill no)
			(layer "F.Fab")
		)
		(pad "1" smd custom
			(at 0 -0.4445 180)
			(size 0.1397 0.1397)
			(layers "F.Cu" "F.Mask" "F.Paste")
			(net "P5VB_LL")
			(options
				(clearance outline)
				(anchor circle)
			)
			(primitives
				(gr_poly
					(pts
						(arc
							(start -0.1778 -0.2794)
							(mid -0.249642 -0.249642)
							(end -0.2794 -0.1778)
						)
						(arc
							(start -0.2794 0.1778)
							(mid -0.249642 0.249642)
							(end -0.1778 0.2794)
						)
						(arc
							(start 0.1778 0.2794)
							(mid 0.249642 0.249642)
							(end 0.2794 0.1778)
						)
						(arc
							(start 0.2794 -0.1778)
							(mid 0.249642 -0.249642)
							(end 0.1778 -0.2794)
						)
					)
					(width 0)
					(fill yes)
				)
			)
		)
		(pad "2" smd custom
			(at 0 0.4445 180)
			(size 0.1397 0.1397)
			(layers "F.Cu" "F.Mask" "F.Paste")
			(net "P5VB_LL_NET")
			(options
				(clearance outline)
				(anchor circle)
			)
			(primitives
				(gr_poly
					(pts
						(arc
							(start -0.1778 -0.2794)
							(mid -0.249642 -0.249642)
							(end -0.2794 -0.1778)
						)
						(arc
							(start -0.2794 0.1778)
							(mid -0.249642 0.249642)
							(end -0.1778 0.2794)
						)
						(arc
							(start 0.1778 0.2794)
							(mid 0.249642 0.249642)
							(end 0.2794 0.1778)
						)
						(arc
							(start 0.2794 -0.1778)
							(mid 0.249642 -0.249642)
							(end 0.1778 -0.2794)
						)
					)
					(width 0)
					(fill yes)
				)
			)
		)
	)
	(footprint ""
		(layer "F.Cu")
		(at 41.909746 -434.368702)
		(property "Reference" "Q21"
			(at 0 0 0)
			(layer "F.SilkS")
			(hide yes)
			(effects
				(font
					(size 1.27 1.27)
				)
			)
		)
		(property "Value" "AO4406AL-GP"
			(at -3.707384 -1.5367 0)
			(unlocked yes)
			(layer "F.Fab")
			(hide yes)
			(effects
				(font
					(size 1.016 1.016)
					(thickness 0.1524)
				)
			)
		)
		(property "Device Type" "SOIC8H69"
			(at -3.707384 -3.0607 0)
			(unlocked yes)
			(layer "F.Fab")
			(hide yes)
			(effects
				(font
					(size 1.016 1.016)
					(thickness 0.1524)
				)
			)
		)
		(duplicate_pad_numbers_are_jumpers no)
		(fp_line
			(start -2.7432 -1.4224)
			(end -2.7432 1.4224)
			(stroke
				(width 0.1524)
				(type default)
			)
			(layer "F.SilkS")
		)
		(fp_line
			(start -2.7432 1.4224)
			(end -2.6416 1.4224)
			(stroke
				(width 0.1524)
				(type default)
			)
			(layer "F.SilkS")
		)
		(fp_line
			(start -2.7432 1.4224)
			(end 2.1336 1.4224)
			(stroke
				(width 0.1524)
				(type default)
			)
			(layer "F.SilkS")
		)
		(fp_line
			(start -2.7178 -0.508)
			(end -2.1844 -0.0508)
			(stroke
				(width 0.1524)
				(type default)
			)
			(layer "F.SilkS")
		)
		(fp_line
			(start -2.6289 3.4417)
			(end -2.6289 1.4732)
			(stroke
				(width 0.381)
				(type default)
			)
			(layer "F.SilkS")
		)
		(fp_line
			(start -2.1844 -0.0508)
			(end -2.7178 0.508)
			(stroke
				(width 0.1524)
				(type default)
			)
			(layer "F.SilkS")
		)
		(fp_line
			(start 2.1336 -1.4224)
			(end -2.7432 -1.4224)
			(stroke
				(width 0.1524)
				(type default)
			)
			(layer "F.SilkS")
		)
		(fp_line
			(start 2.1336 1.4224)
			(end 2.1336 -1.4224)
			(stroke
				(width 0.1524)
				(type default)
			)
			(layer "F.SilkS")
		)
		(fp_poly
			(pts
				(xy -2.2098 -1.4224) (xy -2.2098 1.4224) (xy 2.2098 1.4224) (xy 2.2098 -1.4224)
			)
			(stroke
				(width 0)
				(type default)
			)
			(fill yes)
			(layer "F.SilkS")
		)
		(fp_rect
			(start -2.450084 2.999994)
			(end 2.450084 -2.999994)
			(stroke
				(width 0)
				(type default)
			)
			(fill no)
			(layer "F.CrtYd")
		)
		(fp_poly
			(pts
				(xy -2.8194 3.6322) (xy -2.8194 -3.6322) (xy 2.8194 -3.6322) (xy 2.8194 1.18364) (xy 2.450084 1.18364)
				(xy 2.450084 -2.999994) (xy -2.450084 -2.999994) (xy -2.450084 2.999994) (xy 2.450084 2.999994)
				(xy 2.450084 1.18618) (xy 2.8194 1.18618) (xy 2.8194 3.6322)
			)
			(stroke
				(width 0)
				(type default)
			)
			(fill no)
			(layer "F.CrtYd")
		)
		(fp_rect
			(start -2.8194 3.6322)
			(end 2.8194 -3.6322)
			(stroke
				(width 0)
				(type default)
			)
			(fill no)
			(layer "F.Fab")
		)
		(pad "1" smd rect
			(at -1.905 2.54)
			(size 0.635 1.651)
			(layers "F.Cu" "F.Mask" "F.Paste")
			(net "P5V_HDD10")
		)
		(pad "2" smd rect
			(at -0.635 2.54)
			(size 0.635 1.651)
			(layers "F.Cu" "F.Mask" "F.Paste")
			(net "P5V_HDD10")
		)
		(pad "3" smd rect
			(at 0.635 2.54)
			(size 0.635 1.651)
			(layers "F.Cu" "F.Mask" "F.Paste")
			(net "P5V_HDD10")
		)
		(pad "4" smd rect
			(at 1.905 2.54)
			(size 0.635 1.651)
			(layers "F.Cu" "F.Mask" "F.Paste")
			(net "SW_HDD10_P")
		)
		(pad "5" smd rect
			(at 1.905 -2.54)
			(size 0.635 1.651)
			(layers "F.Cu" "F.Mask" "F.Paste")
			(net "P5VC")
		)
		(pad "6" smd rect
			(at 0.635 -2.54)
			(size 0.635 1.651)
			(layers "F.Cu" "F.Mask" "F.Paste")
			(net "P5VC")
		)
		(pad "7" smd rect
			(at -0.635 -2.54)
			(size 0.635 1.651)
			(layers "F.Cu" "F.Mask" "F.Paste")
			(net "P5VC")
		)
		(pad "8" smd rect
			(at -1.905 -2.54)
			(size 0.635 1.651)
			(layers "F.Cu" "F.Mask" "F.Paste")
			(net "P5VC")
		)
	)
)
